FILE_TYPE = CONNECTIVITY;
{Allegro Design Entry HDL 17.4-2019 S026 (4007227) 1/17/2022}
"PAGE_NUMBER" = 271;
0"NC";
1"GND\g";
2"P3V3_AUX\g";
3"GND\g";
4"GND\g";
5"GND\g";
6"P3V3_AUX\g";
7"NC_HSC_TYPE_VINM";
8"HSC_TYPE_ADC";
9"SMB_LM75_0_3V3AUX_SDA";
10"SMB_LM75_0_3V3AUX_SCL";
11"SMB_HSC_TYPE_ADC_SCL";
12"NC_HSC_TYPE_NC5";
13"NC_HSC_TYPE_NC4";
14"NC_HSC_TYPE_NC3";
15"NC_HSC_TYPE_NC2";
16"NC_HSC_TYPE_NC1";
17"NC_HSC_TYPE_NC0";
18"HSC_TYPE_ADC_ALERT";
19"NC_HSC_TYPE_VINP";
20"SMB_HSC_TYPE_ADC_SDA";
21"HSC_TYPE_ADC_A0";
22"HSC_TYPE_ADC_A1";
%"Q_RES"
"1","(-6225,5300)","0","pure_quanta","I10";
;
LOCATION"R6253"
$SEC"1"
CDS_SEC"1"
MATERIAL"CHIP"
TOLERANCE"1%"
VALUE"33.2"
WATTAGE"1/16W"
PACK_TYPE"0402LF"
CDS_LIB"pure_quanta"
PART_NUMBER"CS03322FB03";
"B"
$PN"2"20;
"A"
$PN"1"9;
%"Q_CAP"
"1","(-6175,4975)","0","pure_quanta","I11";
;
LOCATION"C6086"
$SEC"1"
CDS_SEC"1"
VOLTAGE"25V"
VALUE"0.1UF"
TOLERANCE"10%"
PACK_TYPE"0402"
MATERIAL"X7R"
CDS_LIB"pure_quanta"
PART_NUMBER"CH4104K1B00";
"B"
$PN"2"3;
"A"
$PN"1"8;
%"UNIVERSAL_GND"
"1","(-7575,5475)","0","pure_quanta_power","I13";
;
CDS_LIB"pure_quanta_power"
HDL_POWER"GND";
"A"4;
%"Q_RES"
"1","(-7025,5625)","0","pure_quanta","I14";
;
LOCATION"R6251"
$SEC"1"
CDS_SEC"1"
WATTAGE"1/16W"
VALUE"4.7K"
TOLERANCE"1%"
MATERIAL"EMPTY"
PACK_TYPE"0402LF"
CDS_LIB"pure_quanta"
PART_NUMBER"CS24702FB06";
"B"
$PN"2"21;
"A"
$PN"1"4;
%"UNIVERSAL_GND"
"1","(-4000,4700)","0","pure_quanta_power","I18";
;
CDS_LIB"pure_quanta_power"
HDL_POWER"GND";
"A"5;
%"UNIVERSAL_GND"
"1","(-5325,5725)","0","pure_quanta_power","I21";
;
CDS_LIB"pure_quanta_power"
HDL_POWER"GND";
"A"1;
%"Q_CAP"
"1","(-5325,5950)","0","pure_quanta","I22";
;
LOCATION"C6087"
$SEC"1"
CDS_SEC"1"
PACK_TYPE"0402"
TOLERANCE"10%"
VOLTAGE"25V"
VALUE"0.1UF"
MATERIAL"X7R"
CDS_LIB"pure_quanta"
PART_NUMBER"CH4104K1B00";
"B"
$PN"2"1;
"A"
$PN"1"6;
%"UNIVERSAL_POWER"
"1","(-5075,6350)","0","pure_quanta_power","I23";
;
HDL_POWER"P3V3_AUX"
CDS_LIB"pure_quanta_power";
"A"6;
%"Q_RES"
"2","(-3375,6050)","0","pure_quanta","I25";
;
LOCATION"R6247"
$SEC"1"
CDS_SEC"1"
PACK_TYPE"0402LF"
MATERIAL"CHIP"
WATTAGE"1/16W"
TOLERANCE"1%"
VALUE"4.7K"
CDS_LIB"pure_quanta"
PART_NUMBER"CS24702FB06";
"A"
$PN"1"2;
"B"
$PN"2"18;
%"UNIVERSAL_POWER"
"1","(-3375,6250)","0","pure_quanta_power","I26";
;
HDL_POWER"P3V3_AUX"
CDS_LIB"pure_quanta_power";
"A"2;
%"ISL28022FRZT"
"1","(-4575,5350)","0","pure_quanta","I28";
;
LOCATION"U6005"
SEC"1"
VALUE"ISL28022FRZ-T"
PART_TYPE"SMLF"
MATERIAL"IC"
SEC_TYPE""
CDS_LMAN_SYM_OUTLINE"-300,300,300,-300"
NEEDS_NO_SIZE"TRUE"
CDS_LIB"pure_quanta"
PART_NUMBER"AL028022003";
"TH_GND"
$PN"TH"5;
"GND"
$PN"10"5;
"NC5"
$PN"16"12;
"NC4"
$PN"15"13;
"NC3"
$PN"14"14;
"NC2"
$PN"8"15;
"NC1"
$PN"7"16;
"NC0"
$PN"6"17;
"EXT_CLK||INT"
$PN"3"18;
"VINM"
$PN"12"7;
"VINP"
$PN"13"19;
"VBUS"
$PN"11"8;
"SDA||SMBDAT"
$PN"4"20;
"SCL|||SMBCLK"
$PN"5"11;
"A0"
$PN"2"21;
"A1"
$PN"1"22;
"VCC"
$PN"9"6;
%"Q_RES"
"2","(-5825,5500)","0","pure_quanta","I29";
;
LOCATION"R6254"
$SEC"1"
CDS_SEC"1"
MATERIAL"CHIP"
VALUE"0"
TOLERANCE"5%"
PACK_TYPE"0402LF"
WATTAGE"1/16W"
CDS_LIB"pure_quanta"
PART_NUMBER"CS00002JB13";
"A"
$PN"1"21;
"B"
$PN"2"20;
%"UNIVERSAL_GND"
"1","(-6175,4675)","0","pure_quanta_power","I3";
;
CDS_LIB"pure_quanta_power"
HDL_POWER"GND";
"A"3;
%"Q_RES"
"1","(-7025,5675)","0","pure_quanta","I30";
;
LOCATION"R6250"
$SEC"1"
CDS_SEC"1"
VALUE"4.7K"
PACK_TYPE"0402LF"
MATERIAL"CHIP"
TOLERANCE"1%"
WATTAGE"1/16W"
CDS_LIB"pure_quanta"
PART_NUMBER"CS24702FB06";
"B"
$PN"2"22;
"A"
$PN"1"4;
%"Q_RES"
"1","(-6225,5350)","0","pure_quanta","I9";
;
LOCATION"R6252"
$SEC"1"
CDS_SEC"1"
MATERIAL"CHIP"
TOLERANCE"1%"
WATTAGE"1/16W"
PACK_TYPE"0402LF"
VALUE"33.2"
CDS_LIB"pure_quanta"
PART_NUMBER"CS03322FB03";
"B"
$PN"2"11;
"A"
$PN"1"10;
END.
